(kicad_pcb
	(version 20260206)
	(generator "pcbnew")
	(generator_version "10.0")
	(general
		(thickness 1.6)
		(legacy_teardrops no)
	)
	(paper "A4")
	(title_block
		(title "04192023_DAF0TMB3IC0_F0TG_MB_C_brd_V02_OCP.brd")
		(comment 1 "Grand Teton / footprints 7466-7472 of 8354")
	)
	(layers
		(0 "F.Cu" signal "TOP")
		(4 "In1.Cu" signal "GND")
		(6 "In2.Cu" signal "IN1")
		(8 "In3.Cu" signal "GND1")
		(10 "In4.Cu" signal "IN2")
		(12 "In5.Cu" signal "GND2")
		(14 "In6.Cu" signal "IN3")
		(16 "In7.Cu" signal "GND3")
		(18 "In8.Cu" signal "VCC")
		(20 "In9.Cu" signal "VCC1")
		(22 "In10.Cu" signal "GND4")
		(24 "In11.Cu" signal "IN4")
		(26 "In12.Cu" signal "GND5")
		(28 "In13.Cu" signal "IN5")
		(30 "In14.Cu" signal "GND6")
		(32 "In15.Cu" signal "IN6")
		(34 "In16.Cu" signal "GND7")
		(2 "B.Cu" signal "BOTTOM")
		(9 "F.Adhes" user "F.Adhesive")
		(11 "B.Adhes" user "B.Adhesive")
		(13 "F.Paste" user "Package Geometry/Pastemask Top")
		(15 "B.Paste" user "Package Geometry/Pastemask Bottom")
		(5 "F.SilkS" user "Ref Des/Silkscreen Top")
		(7 "B.SilkS" user "Ref Des/Silkscreen Bottom")
		(1 "F.Mask" user "Board Geometry/Soldermask Top")
		(3 "B.Mask" user "Board Geometry/Soldermask Bottom")
		(17 "Dwgs.User" user "User.Drawings")
		(19 "Cmts.User" user "User.Comments")
		(21 "Eco1.User" user "User.Eco1")
		(23 "Eco2.User" user "User.Eco2")
		(25 "Edge.Cuts" user "Board Geometry/Outline")
		(27 "Margin" user)
		(31 "F.CrtYd" user "Package Geometry/Place Bound Top")
		(29 "B.CrtYd" user "Package Geometry/Place Bound Bottom")
		(35 "F.Fab" user "Ref Des/Assembly Top")
		(33 "B.Fab" user "Ref Des/Assembly Bottom")
	)
	(footprint ""
		(layer "B.Cu")
		(at 142.893542 -383.7432 180)
		(property "Reference" "R869"
			(at 0 0 0)
			(layer "B.SilkS")
			(hide yes)
			(effects
				(font
					(size 1.27 1.27)
				)
				(justify mirror)
			)
		)
		(property "Value" ""
			(at 0 0 0)
			(layer "B.Fab")
			(effects
				(font
					(size 1.27 1.27)
				)
				(justify mirror)
			)
		)
		(duplicate_pad_numbers_are_jumpers no)
		(fp_line
			(start 0.32512 0.175006)
			(end 0.32512 -0.175006)
			(stroke
				(width 0.1)
				(type default)
			)
			(layer "B.Fab")
		)
		(fp_line
			(start 0.32512 -0.175006)
			(end -0.32512 -0.175006)
			(stroke
				(width 0.1)
				(type default)
			)
			(layer "B.Fab")
		)
		(fp_line
			(start -0.32512 0.175006)
			(end 0.32512 0.175006)
			(stroke
				(width 0.1)
				(type default)
			)
			(layer "B.Fab")
		)
		(fp_line
			(start -0.32512 -0.175006)
			(end -0.32512 0.175006)
			(stroke
				(width 0.1)
				(type default)
			)
			(layer "B.Fab")
		)
		(pad "1" smd rect
			(at 0.2667 0)
			(size 0.3048 0.381)
			(layers "B.Cu" "B.Mask" "B.Paste")
			(net "RT_CPU1_P2_SCAN_MODE")
		)
		(pad "2" smd rect
			(at -0.2667 0 180)
			(size 0.3048 0.381)
			(layers "B.Cu" "B.Mask" "B.Paste")
			(net "GND")
		)
	)
	(footprint ""
		(layer "B.Cu")
		(at 197.269608 -107.529376 180)
		(property "Reference" "R285"
			(at 0 0 0)
			(layer "B.SilkS")
			(hide yes)
			(effects
				(font
					(size 1.27 1.27)
				)
				(justify mirror)
			)
		)
		(property "Value" ""
			(at 0 0 0)
			(layer "B.Fab")
			(effects
				(font
					(size 1.27 1.27)
				)
				(justify mirror)
			)
		)
		(duplicate_pad_numbers_are_jumpers no)
		(fp_line
			(start 0.7874 0.4064)
			(end 0.7874 -0.4064)
			(stroke
				(width 0.1524)
				(type default)
			)
			(layer "B.SilkS")
		)
		(fp_line
			(start 0.7874 -0.4064)
			(end -0.7874 -0.4064)
			(stroke
				(width 0.1524)
				(type default)
			)
			(layer "B.SilkS")
		)
		(fp_line
			(start -0.7874 0.4064)
			(end 0.7874 0.4064)
			(stroke
				(width 0.1524)
				(type default)
			)
			(layer "B.SilkS")
		)
		(fp_line
			(start -0.7874 -0.4064)
			(end -0.7874 0.4064)
			(stroke
				(width 0.1524)
				(type default)
			)
			(layer "B.SilkS")
		)
		(fp_line
			(start 0.67945 0.3048)
			(end 0.67945 -0.305054)
			(stroke
				(width 0.1)
				(type default)
			)
			(layer "B.Fab")
		)
		(fp_line
			(start 0.67945 -0.305054)
			(end 0.12065 -0.305054)
			(stroke
				(width 0.1)
				(type default)
			)
			(layer "B.Fab")
		)
		(fp_line
			(start 0.12065 0.3048)
			(end 0.67945 0.3048)
			(stroke
				(width 0.1)
				(type default)
			)
			(layer "B.Fab")
		)
		(fp_line
			(start 0.12065 0.2794)
			(end 0.12065 0.3048)
			(stroke
				(width 0.1)
				(type default)
			)
			(layer "B.Fab")
		)
		(fp_line
			(start 0.12065 -0.2794)
			(end -0.12065 -0.2794)
			(stroke
				(width 0.1)
				(type default)
			)
			(layer "B.Fab")
		)
		(fp_line
			(start 0.12065 -0.305054)
			(end 0.12065 -0.2794)
			(stroke
				(width 0.1)
				(type default)
			)
			(layer "B.Fab")
		)
		(fp_line
			(start -0.120396 0.3048)
			(end -0.120396 0.2794)
			(stroke
				(width 0.1)
				(type default)
			)
			(layer "B.Fab")
		)
		(fp_line
			(start -0.120396 0.2794)
			(end 0.12065 0.2794)
			(stroke
				(width 0.1)
				(type default)
			)
			(layer "B.Fab")
		)
		(fp_line
			(start -0.12065 -0.2794)
			(end -0.12065 -0.3048)
			(stroke
				(width 0.1)
				(type default)
			)
			(layer "B.Fab")
		)
		(fp_line
			(start -0.12065 -0.3048)
			(end -0.67945 -0.3048)
			(stroke
				(width 0.1)
				(type default)
			)
			(layer "B.Fab")
		)
		(fp_line
			(start -0.67945 0.3048)
			(end -0.120396 0.3048)
			(stroke
				(width 0.1)
				(type default)
			)
			(layer "B.Fab")
		)
		(fp_line
			(start -0.67945 -0.3048)
			(end -0.67945 0.3048)
			(stroke
				(width 0.1)
				(type default)
			)
			(layer "B.Fab")
		)
		(pad "1" smd circle
			(at 0.40005 0)
			(size 0 0)
			(layers "B.Cu" "B.Mask" "B.Paste")
			(net "FM_PVDDCR_CPU1_P1_R_EN")
		)
		(pad "2" smd circle
			(at -0.40005 0)
			(size 0 0)
			(layers "B.Cu" "B.Mask" "B.Paste")
			(net "FM_PVDDCR_CPU1_P1_EN")
		)
	)
	(footprint ""
		(layer "B.Cu")
		(at 197.955408 -122.769376 180)
		(property "Reference" "R3485"
			(at 0 0 0)
			(layer "B.SilkS")
			(hide yes)
			(effects
				(font
					(size 1.27 1.27)
				)
				(justify mirror)
			)
		)
		(property "Value" ""
			(at 0 0 0)
			(layer "B.Fab")
			(effects
				(font
					(size 1.27 1.27)
				)
				(justify mirror)
			)
		)
		(duplicate_pad_numbers_are_jumpers no)
		(fp_line
			(start 0.7874 0.4064)
			(end 0.7874 -0.4064)
			(stroke
				(width 0.1524)
				(type default)
			)
			(layer "B.SilkS")
		)
		(fp_line
			(start 0.7874 -0.4064)
			(end -0.7874 -0.4064)
			(stroke
				(width 0.1524)
				(type default)
			)
			(layer "B.SilkS")
		)
		(fp_line
			(start -0.7874 0.4064)
			(end 0.7874 0.4064)
			(stroke
				(width 0.1524)
				(type default)
			)
			(layer "B.SilkS")
		)
		(fp_line
			(start -0.7874 -0.4064)
			(end -0.7874 0.4064)
			(stroke
				(width 0.1524)
				(type default)
			)
			(layer "B.SilkS")
		)
		(fp_line
			(start 0.67945 0.3048)
			(end 0.67945 -0.305054)
			(stroke
				(width 0.1)
				(type default)
			)
			(layer "B.Fab")
		)
		(fp_line
			(start 0.67945 -0.305054)
			(end 0.12065 -0.305054)
			(stroke
				(width 0.1)
				(type default)
			)
			(layer "B.Fab")
		)
		(fp_line
			(start 0.12065 0.3048)
			(end 0.67945 0.3048)
			(stroke
				(width 0.1)
				(type default)
			)
			(layer "B.Fab")
		)
		(fp_line
			(start 0.12065 0.2794)
			(end 0.12065 0.3048)
			(stroke
				(width 0.1)
				(type default)
			)
			(layer "B.Fab")
		)
		(fp_line
			(start 0.12065 -0.2794)
			(end -0.12065 -0.2794)
			(stroke
				(width 0.1)
				(type default)
			)
			(layer "B.Fab")
		)
		(fp_line
			(start 0.12065 -0.305054)
			(end 0.12065 -0.2794)
			(stroke
				(width 0.1)
				(type default)
			)
			(layer "B.Fab")
		)
		(fp_line
			(start -0.120396 0.3048)
			(end -0.120396 0.2794)
			(stroke
				(width 0.1)
				(type default)
			)
			(layer "B.Fab")
		)
		(fp_line
			(start -0.120396 0.2794)
			(end 0.12065 0.2794)
			(stroke
				(width 0.1)
				(type default)
			)
			(layer "B.Fab")
		)
		(fp_line
			(start -0.12065 -0.2794)
			(end -0.12065 -0.3048)
			(stroke
				(width 0.1)
				(type default)
			)
			(layer "B.Fab")
		)
		(fp_line
			(start -0.12065 -0.3048)
			(end -0.67945 -0.3048)
			(stroke
				(width 0.1)
				(type default)
			)
			(layer "B.Fab")
		)
		(fp_line
			(start -0.67945 0.3048)
			(end -0.120396 0.3048)
			(stroke
				(width 0.1)
				(type default)
			)
			(layer "B.Fab")
		)
		(fp_line
			(start -0.67945 -0.3048)
			(end -0.67945 0.3048)
			(stroke
				(width 0.1)
				(type default)
			)
			(layer "B.Fab")
		)
		(pad "1" smd circle
			(at 0.40005 0)
			(size 0 0)
			(layers "B.Cu" "B.Mask" "B.Paste")
			(net "GPU_WP_HW_CTRL_R_N")
		)
		(pad "2" smd circle
			(at -0.40005 0)
			(size 0 0)
			(layers "B.Cu" "B.Mask" "B.Paste")
			(net "GPU_WP_HW_CTRL_N")
		)
	)
	(footprint ""
		(layer "B.Cu")
		(at 168.528238 -192.66027)
		(property "Reference" "C530"
			(at 0 0 0)
			(layer "B.SilkS")
			(hide yes)
			(effects
				(font
					(size 1.27 1.27)
				)
				(justify mirror)
			)
		)
		(property "Value" ""
			(at 0 0 0)
			(layer "B.Fab")
			(effects
				(font
					(size 1.27 1.27)
				)
				(justify mirror)
			)
		)
		(duplicate_pad_numbers_are_jumpers no)
		(fp_line
			(start -1.524 -0.762)
			(end -1.524 0.762)
			(stroke
				(width 0.1524)
				(type default)
			)
			(layer "B.SilkS")
		)
		(fp_line
			(start -1.524 0.762)
			(end 1.524 0.762)
			(stroke
				(width 0.1524)
				(type default)
			)
			(layer "B.SilkS")
		)
		(fp_line
			(start 1.524 -0.762)
			(end -1.524 -0.762)
			(stroke
				(width 0.1524)
				(type default)
			)
			(layer "B.SilkS")
		)
		(fp_line
			(start 1.524 0.762)
			(end 1.524 -0.762)
			(stroke
				(width 0.1524)
				(type default)
			)
			(layer "B.SilkS")
		)
		(fp_line
			(start -1.1049 -0.724916)
			(end 1.1049 -0.724916)
			(stroke
				(width 0.1)
				(type default)
			)
			(layer "B.Fab")
		)
		(fp_line
			(start -1.1049 0.724916)
			(end -1.1049 -0.724916)
			(stroke
				(width 0.1)
				(type default)
			)
			(layer "B.Fab")
		)
		(fp_line
			(start 1.1049 -0.724916)
			(end 1.1049 0.724916)
			(stroke
				(width 0.1)
				(type default)
			)
			(layer "B.Fab")
		)
		(fp_line
			(start 1.1049 0.724916)
			(end -1.1049 0.724916)
			(stroke
				(width 0.1)
				(type default)
			)
			(layer "B.Fab")
		)
		(pad "1" smd rect
			(at 0.889 0)
			(size 1.016 1.27)
			(layers "B.Cu" "B.Mask" "B.Paste")
			(net "P12V_MEM_CPU1")
		)
		(pad "2" smd rect
			(at -0.889 0)
			(size 1.016 1.27)
			(layers "B.Cu" "B.Mask" "B.Paste")
			(net "GND")
		)
	)
	(footprint ""
		(layer "B.Cu")
		(at 187.060078 -192.66027 180)
		(property "Reference" "C537"
			(at 0 0 0)
			(layer "B.SilkS")
			(hide yes)
			(effects
				(font
					(size 1.27 1.27)
				)
				(justify mirror)
			)
		)
		(property "Value" ""
			(at 0 0 0)
			(layer "B.Fab")
			(effects
				(font
					(size 1.27 1.27)
				)
				(justify mirror)
			)
		)
		(duplicate_pad_numbers_are_jumpers no)
		(fp_line
			(start 1.524 0.762)
			(end 1.524 -0.762)
			(stroke
				(width 0.1524)
				(type default)
			)
			(layer "B.SilkS")
		)
		(fp_line
			(start 1.524 -0.762)
			(end -1.524 -0.762)
			(stroke
				(width 0.1524)
				(type default)
			)
			(layer "B.SilkS")
		)
		(fp_line
			(start -1.524 0.762)
			(end 1.524 0.762)
			(stroke
				(width 0.1524)
				(type default)
			)
			(layer "B.SilkS")
		)
		(fp_line
			(start -1.524 -0.762)
			(end -1.524 0.762)
			(stroke
				(width 0.1524)
				(type default)
			)
			(layer "B.SilkS")
		)
		(fp_line
			(start 1.1049 0.724916)
			(end -1.1049 0.724916)
			(stroke
				(width 0.1)
				(type default)
			)
			(layer "B.Fab")
		)
		(fp_line
			(start 1.1049 -0.724916)
			(end 1.1049 0.724916)
			(stroke
				(width 0.1)
				(type default)
			)
			(layer "B.Fab")
		)
		(fp_line
			(start -1.1049 0.724916)
			(end -1.1049 -0.724916)
			(stroke
				(width 0.1)
				(type default)
			)
			(layer "B.Fab")
		)
		(fp_line
			(start -1.1049 -0.724916)
			(end 1.1049 -0.724916)
			(stroke
				(width 0.1)
				(type default)
			)
			(layer "B.Fab")
		)
		(pad "1" smd rect
			(at 0.889 0 180)
			(size 1.016 1.27)
			(layers "B.Cu" "B.Mask" "B.Paste")
			(net "P12V_MEM_CPU1")
		)
		(pad "2" smd rect
			(at -0.889 0 180)
			(size 1.016 1.27)
			(layers "B.Cu" "B.Mask" "B.Paste")
			(net "GND")
		)
	)
	(footprint ""
		(layer "B.Cu")
		(at 132.865114 -33.199578 -90)
		(property "Reference" "C6049"
			(at 0 0 90)
			(layer "B.SilkS")
			(hide yes)
			(effects
				(font
					(size 1.27 1.27)
				)
				(justify mirror)
			)
		)
		(property "Value" ""
			(at 0 0 90)
			(layer "B.Fab")
			(effects
				(font
					(size 1.27 1.27)
				)
				(justify mirror)
			)
		)
		(duplicate_pad_numbers_are_jumpers no)
		(fp_line
			(start -0.7874 0.4064)
			(end 0.7874 0.4064)
			(stroke
				(width 0.1524)
				(type default)
			)
			(layer "B.SilkS")
		)
		(fp_line
			(start 0.7874 0.4064)
			(end 0.7874 -0.4064)
			(stroke
				(width 0.1524)
				(type default)
			)
			(layer "B.SilkS")
		)
		(fp_line
			(start -0.7874 -0.4064)
			(end -0.7874 0.4064)
			(stroke
				(width 0.1524)
				(type default)
			)
			(layer "B.SilkS")
		)
		(fp_line
			(start 0.7874 -0.4064)
			(end -0.7874 -0.4064)
			(stroke
				(width 0.1524)
				(type default)
			)
			(layer "B.SilkS")
		)
		(fp_line
			(start -0.67945 0.3048)
			(end -0.120396 0.3048)
			(stroke
				(width 0.1)
				(type default)
			)
			(layer "B.Fab")
		)
		(fp_line
			(start -0.120396 0.3048)
			(end -0.120396 0.2794)
			(stroke
				(width 0.1)
				(type default)
			)
			(layer "B.Fab")
		)
		(fp_line
			(start 0.12065 0.3048)
			(end 0.67945 0.3048)
			(stroke
				(width 0.1)
				(type default)
			)
			(layer "B.Fab")
		)
		(fp_line
			(start 0.67945 0.3048)
			(end 0.67945 -0.305054)
			(stroke
				(width 0.1)
				(type default)
			)
			(layer "B.Fab")
		)
		(fp_line
			(start -0.120396 0.2794)
			(end 0.12065 0.2794)
			(stroke
				(width 0.1)
				(type default)
			)
			(layer "B.Fab")
		)
		(fp_line
			(start 0.12065 0.2794)
			(end 0.12065 0.3048)
			(stroke
				(width 0.1)
				(type default)
			)
			(layer "B.Fab")
		)
		(fp_line
			(start -0.12065 -0.2794)
			(end -0.12065 -0.3048)
			(stroke
				(width 0.1)
				(type default)
			)
			(layer "B.Fab")
		)
		(fp_line
			(start 0.12065 -0.2794)
			(end -0.12065 -0.2794)
			(stroke
				(width 0.1)
				(type default)
			)
			(layer "B.Fab")
		)
		(fp_line
			(start -0.67945 -0.3048)
			(end -0.67945 0.3048)
			(stroke
				(width 0.1)
				(type default)
			)
			(layer "B.Fab")
		)
		(fp_line
			(start -0.12065 -0.3048)
			(end -0.67945 -0.3048)
			(stroke
				(width 0.1)
				(type default)
			)
			(layer "B.Fab")
		)
		(fp_line
			(start 0.12065 -0.305054)
			(end 0.12065 -0.2794)
			(stroke
				(width 0.1)
				(type default)
			)
			(layer "B.Fab")
		)
		(fp_line
			(start 0.67945 -0.305054)
			(end 0.12065 -0.305054)
			(stroke
				(width 0.1)
				(type default)
			)
			(layer "B.Fab")
		)
		(pad "1" smd circle
			(at 0.40005 0 90)
			(size 0 0)
			(layers "B.Cu" "B.Mask" "B.Paste")
			(net "P3V3_AUX")
		)
		(pad "2" smd circle
			(at -0.40005 0 90)
			(size 0 0)
			(layers "B.Cu" "B.Mask" "B.Paste")
			(net "GND")
		)
	)
	(footprint ""
		(layer "B.Cu")
		(at 233.68 -228.092)
		(property "Reference" "R162"
			(at 0 0 0)
			(layer "B.SilkS")
			(hide yes)
			(effects
				(font
					(size 1.27 1.27)
				)
				(justify mirror)
			)
		)
		(property "Value" ""
			(at 0 0 0)
			(layer "B.Fab")
			(effects
				(font
					(size 1.27 1.27)
				)
				(justify mirror)
			)
		)
		(duplicate_pad_numbers_are_jumpers no)
		(fp_line
			(start -0.7874 -0.4064)
			(end -0.7874 0.4064)
			(stroke
				(width 0.1524)
				(type default)
			)
			(layer "B.SilkS")
		)
		(fp_line
			(start -0.7874 0.4064)
			(end 0.7874 0.4064)
			(stroke
				(width 0.1524)
				(type default)
			)
			(layer "B.SilkS")
		)
		(fp_line
			(start 0.7874 -0.4064)
			(end -0.7874 -0.4064)
			(stroke
				(width 0.1524)
				(type default)
			)
			(layer "B.SilkS")
		)
		(fp_line
			(start 0.7874 0.4064)
			(end 0.7874 -0.4064)
			(stroke
				(width 0.1524)
				(type default)
			)
			(layer "B.SilkS")
		)
		(fp_line
			(start -0.67945 -0.3048)
			(end -0.67945 0.3048)
			(stroke
				(width 0.1)
				(type default)
			)
			(layer "B.Fab")
		)
		(fp_line
			(start -0.67945 0.3048)
			(end -0.120396 0.3048)
			(stroke
				(width 0.1)
				(type default)
			)
			(layer "B.Fab")
		)
		(fp_line
			(start -0.12065 -0.3048)
			(end -0.67945 -0.3048)
			(stroke
				(width 0.1)
				(type default)
			)
			(layer "B.Fab")
		)
		(fp_line
			(start -0.12065 -0.2794)
			(end -0.12065 -0.3048)
			(stroke
				(width 0.1)
				(type default)
			)
			(layer "B.Fab")
		)
		(fp_line
			(start -0.120396 0.2794)
			(end 0.12065 0.2794)
			(stroke
				(width 0.1)
				(type default)
			)
			(layer "B.Fab")
		)
		(fp_line
			(start -0.120396 0.3048)
			(end -0.120396 0.2794)
			(stroke
				(width 0.1)
				(type default)
			)
			(layer "B.Fab")
		)
		(fp_line
			(start 0.12065 -0.305054)
			(end 0.12065 -0.2794)
			(stroke
				(width 0.1)
				(type default)
			)
			(layer "B.Fab")
		)
		(fp_line
			(start 0.12065 -0.2794)
			(end -0.12065 -0.2794)
			(stroke
				(width 0.1)
				(type default)
			)
			(layer "B.Fab")
		)
		(fp_line
			(start 0.12065 0.2794)
			(end 0.12065 0.3048)
			(stroke
				(width 0.1)
				(type default)
			)
			(layer "B.Fab")
		)
		(fp_line
			(start 0.12065 0.3048)
			(end 0.67945 0.3048)
			(stroke
				(width 0.1)
				(type default)
			)
			(layer "B.Fab")
		)
		(fp_line
			(start 0.67945 -0.305054)
			(end 0.12065 -0.305054)
			(stroke
				(width 0.1)
				(type default)
			)
			(layer "B.Fab")
		)
		(fp_line
			(start 0.67945 0.3048)
			(end 0.67945 -0.305054)
			(stroke
				(width 0.1)
				(type default)
			)
			(layer "B.Fab")
		)
		(pad "1" smd rect
			(at 0.40005 0)
			(size 0.4572 0.508)
			(layers "B.Cu" "B.Mask" "B.Paste")
			(net "SMB_CPU0_CPU1_APML_SDA")
		)
		(pad "2" smd rect
			(at -0.40005 0)
			(size 0.4572 0.508)
			(layers "B.Cu" "B.Mask" "B.Paste")
			(net "SMB_CPU0_CPU1_APML_BUF2_SDA")
		)
	)
)
